# T6G (Grand Teton) — schematic netlist excerpt (pin names and nets, part order shuffled) for the footprints in the layout excerpt that follows; sources: Cadence DE-HDL packaged netlist, KiCad conversion of 04192023_DAF0TMB3IC0_F0TG_MB_C_brd_V02_OCP.brd

R1249  Q_RES  0 5% EMPTY  pkg 0402LF  page 258 : A = PVDD18_S5_P1_ADC ; B = PVDD18_S5_P1_ADC_MAM
R1575  Q_RES  49.9 1% CHIP  pkg 0402LF  page 93 : A = I3C_SPD_DDRGL_CPU0_SCL ; B = I3C_SPD_DDRH_CPU0_SCL

(kicad_pcb
	(version 20260206)
	(generator "pcbnew")
	(generator_version "10.0")
	(general
		(thickness 1.6)
		(legacy_teardrops no)
	)
	(paper "A4")
	(title_block
		(title "04192023_DAF0TMB3IC0_F0TG_MB_C_brd_V02_OCP.brd")
		(comment 1 "Grand Teton / footprints 5948-5949 of 8354")
	)
	(layers
		(0 "F.Cu" signal "TOP")
		(4 "In1.Cu" signal "GND")
		(6 "In2.Cu" signal "IN1")
		(8 "In3.Cu" signal "GND1")
		(10 "In4.Cu" signal "IN2")
		(12 "In5.Cu" signal "GND2")
		(14 "In6.Cu" signal "IN3")
		(16 "In7.Cu" signal "GND3")
		(18 "In8.Cu" signal "VCC")
		(20 "In9.Cu" signal "VCC1")
		(22 "In10.Cu" signal "GND4")
		(24 "In11.Cu" signal "IN4")
		(26 "In12.Cu" signal "GND5")
		(28 "In13.Cu" signal "IN5")
		(30 "In14.Cu" signal "GND6")
		(32 "In15.Cu" signal "IN6")
		(34 "In16.Cu" signal "GND7")
		(2 "B.Cu" signal "BOTTOM")
		(9 "F.Adhes" user "F.Adhesive")
		(11 "B.Adhes" user "B.Adhesive")
		(13 "F.Paste" user "Package Geometry/Pastemask Top")
		(15 "B.Paste" user "Package Geometry/Pastemask Bottom")
		(5 "F.SilkS" user "Ref Des/Silkscreen Top")
		(7 "B.SilkS" user "Ref Des/Silkscreen Bottom")
		(1 "F.Mask" user "Board Geometry/Soldermask Top")
		(3 "B.Mask" user "Board Geometry/Soldermask Bottom")
		(17 "Dwgs.User" user "User.Drawings")
		(19 "Cmts.User" user "User.Comments")
		(21 "Eco1.User" user "User.Eco1")
		(23 "Eco2.User" user "User.Eco2")
		(25 "Edge.Cuts" user "Board Geometry/Outline")
		(27 "Margin" user)
		(31 "F.CrtYd" user "Package Geometry/Place Bound Top")
		(29 "B.CrtYd" user "Package Geometry/Place Bound Bottom")
		(35 "F.Fab" user "Ref Des/Assembly Top")
		(33 "B.Fab" user "Ref Des/Assembly Bottom")
	)
	(footprint ""
		(layer "B.Cu")
		(at 231.829102 -329.365102 180)
		(property "Reference" "R1249"
			(at 0 0 0)
			(layer "B.SilkS")
			(hide yes)
			(effects
				(font
					(size 1.27 1.27)
				)
				(justify mirror)
			)
		)
		(property "Value" ""
			(at 0 0 0)
			(layer "B.Fab")
			(effects
				(font
					(size 1.27 1.27)
				)
				(justify mirror)
			)
		)
		(duplicate_pad_numbers_are_jumpers no)
		(fp_line
			(start 0.7874 0.4064)
			(end 0.7874 -0.4064)
			(stroke
				(width 0.1524)
				(type default)
			)
			(layer "B.SilkS")
		)
		(fp_line
			(start 0.7874 -0.4064)
			(end -0.7874 -0.4064)
			(stroke
				(width 0.1524)
				(type default)
			)
			(layer "B.SilkS")
		)
		(fp_line
			(start -0.7874 0.4064)
			(end 0.7874 0.4064)
			(stroke
				(width 0.1524)
				(type default)
			)
			(layer "B.SilkS")
		)
		(fp_line
			(start -0.7874 -0.4064)
			(end -0.7874 0.4064)
			(stroke
				(width 0.1524)
				(type default)
			)
			(layer "B.SilkS")
		)
		(fp_line
			(start 0.67945 0.3048)
			(end 0.67945 -0.305054)
			(stroke
				(width 0.1)
				(type default)
			)
			(layer "B.Fab")
		)
		(fp_line
			(start 0.67945 -0.305054)
			(end 0.12065 -0.305054)
			(stroke
				(width 0.1)
				(type default)
			)
			(layer "B.Fab")
		)
		(fp_line
			(start 0.12065 0.3048)
			(end 0.67945 0.3048)
			(stroke
				(width 0.1)
				(type default)
			)
			(layer "B.Fab")
		)
		(fp_line
			(start 0.12065 0.2794)
			(end 0.12065 0.3048)
			(stroke
				(width 0.1)
				(type default)
			)
			(layer "B.Fab")
		)
		(fp_line
			(start 0.12065 -0.2794)
			(end -0.12065 -0.2794)
			(stroke
				(width 0.1)
				(type default)
			)
			(layer "B.Fab")
		)
		(fp_line
			(start 0.12065 -0.305054)
			(end 0.12065 -0.2794)
			(stroke
				(width 0.1)
				(type default)
			)
			(layer "B.Fab")
		)
		(fp_line
			(start -0.120396 0.3048)
			(end -0.120396 0.2794)
			(stroke
				(width 0.1)
				(type default)
			)
			(layer "B.Fab")
		)
		(fp_line
			(start -0.120396 0.2794)
			(end 0.12065 0.2794)
			(stroke
				(width 0.1)
				(type default)
			)
			(layer "B.Fab")
		)
		(fp_line
			(start -0.12065 -0.2794)
			(end -0.12065 -0.3048)
			(stroke
				(width 0.1)
				(type default)
			)
			(layer "B.Fab")
		)
		(fp_line
			(start -0.12065 -0.3048)
			(end -0.67945 -0.3048)
			(stroke
				(width 0.1)
				(type default)
			)
			(layer "B.Fab")
		)
		(fp_line
			(start -0.67945 0.3048)
			(end -0.120396 0.3048)
			(stroke
				(width 0.1)
				(type default)
			)
			(layer "B.Fab")
		)
		(fp_line
			(start -0.67945 -0.3048)
			(end -0.67945 0.3048)
			(stroke
				(width 0.1)
				(type default)
			)
			(layer "B.Fab")
		)
		(pad "1" smd rect
			(at 0.40005 0 180)
			(size 0.4572 0.508)
			(layers "B.Cu" "B.Mask" "B.Paste")
			(net "PVDD18_S5_P1_ADC")
		)
		(pad "2" smd rect
			(at -0.40005 0 180)
			(size 0.4572 0.508)
			(layers "B.Cu" "B.Mask" "B.Paste")
			(net "PVDD18_S5_P1_ADC_MAM")
		)
	)
	(footprint ""
		(layer "B.Cu")
		(at 423.256456 -194.88531 180)
		(property "Reference" "R1575"
			(at 0 0 0)
			(layer "B.SilkS")
			(hide yes)
			(effects
				(font
					(size 1.27 1.27)
				)
				(justify mirror)
			)
		)
		(property "Value" ""
			(at 0 0 0)
			(layer "B.Fab")
			(effects
				(font
					(size 1.27 1.27)
				)
				(justify mirror)
			)
		)
		(duplicate_pad_numbers_are_jumpers no)
		(fp_line
			(start 0.7874 0.4064)
			(end 0.7874 -0.4064)
			(stroke
				(width 0.1524)
				(type default)
			)
			(layer "B.SilkS")
		)
		(fp_line
			(start 0.7874 -0.4064)
			(end -0.7874 -0.4064)
			(stroke
				(width 0.1524)
				(type default)
			)
			(layer "B.SilkS")
		)
		(fp_line
			(start -0.7874 0.4064)
			(end 0.7874 0.4064)
			(stroke
				(width 0.1524)
				(type default)
			)
			(layer "B.SilkS")
		)
		(fp_line
			(start -0.7874 -0.4064)
			(end -0.7874 0.4064)
			(stroke
				(width 0.1524)
				(type default)
			)
			(layer "B.SilkS")
		)
		(fp_line
			(start 0.67945 0.3048)
			(end 0.67945 -0.305054)
			(stroke
				(width 0.1)
				(type default)
			)
			(layer "B.Fab")
		)
		(fp_line
			(start 0.67945 -0.305054)
			(end 0.12065 -0.305054)
			(stroke
				(width 0.1)
				(type default)
			)
			(layer "B.Fab")
		)
		(fp_line
			(start 0.12065 0.3048)
			(end 0.67945 0.3048)
			(stroke
				(width 0.1)
				(type default)
			)
			(layer "B.Fab")
		)
		(fp_line
			(start 0.12065 0.2794)
			(end 0.12065 0.3048)
			(stroke
				(width 0.1)
				(type default)
			)
			(layer "B.Fab")
		)
		(fp_line
			(start 0.12065 -0.2794)
			(end -0.12065 -0.2794)
			(stroke
				(width 0.1)
				(type default)
			)
			(layer "B.Fab")
		)
		(fp_line
			(start 0.12065 -0.305054)
			(end 0.12065 -0.2794)
			(stroke
				(width 0.1)
				(type default)
			)
			(layer "B.Fab")
		)
		(fp_line
			(start -0.120396 0.3048)
			(end -0.120396 0.2794)
			(stroke
				(width 0.1)
				(type default)
			)
			(layer "B.Fab")
		)
		(fp_line
			(start -0.120396 0.2794)
			(end 0.12065 0.2794)
			(stroke
				(width 0.1)
				(type default)
			)
			(layer "B.Fab")
		)
		(fp_line
			(start -0.12065 -0.2794)
			(end -0.12065 -0.3048)
			(stroke
				(width 0.1)
				(type default)
			)
			(layer "B.Fab")
		)
		(fp_line
			(start -0.12065 -0.3048)
			(end -0.67945 -0.3048)
			(stroke
				(width 0.1)
				(type default)
			)
			(layer "B.Fab")
		)
		(fp_line
			(start -0.67945 0.3048)
			(end -0.120396 0.3048)
			(stroke
				(width 0.1)
				(type default)
			)
			(layer "B.Fab")
		)
		(fp_line
			(start -0.67945 -0.3048)
			(end -0.67945 0.3048)
			(stroke
				(width 0.1)
				(type default)
			)
			(layer "B.Fab")
		)
		(pad "1" smd circle
			(at 0.40005 0)
			(size 0 0)
			(layers "B.Cu" "B.Mask" "B.Paste")
			(net "I3C_SPD_DDRGL_CPU0_SCL")
		)
		(pad "2" smd circle
			(at -0.40005 0)
			(size 0 0)
			(layers "B.Cu" "B.Mask" "B.Paste")
			(net "I3C_SPD_DDRH_CPU0_SCL")
		)
	)
)
